# T6G (Grand Teton) — schematic netlist excerpt (pin names and nets, part order shuffled) for the footprints in the layout excerpt that follows; sources: Cadence DE-HDL packaged netlist, KiCad conversion of 04192023_DAF0TMB3IC0_F0TG_MB_C_brd_V02_OCP.brd

C387  Q_CAP  1UF 4V 20% X6S  pkg 0201  page 345 : A = P0V9_CPU1_RT2_2A ; B = GND

Q85  MOSFET_NCH_DUAL  PJT138K IC  pkg SOT363XD  page 256
  S1  = GND
  G1  = FM_LED_PWRGD_PVDDCR_CPU1_P1
  D2  = LED_PWRGD_PVDDIO_P1_D
  S2  = GND
  G2  = FM_LED_PWRGD_PVDDIO_P1
  D1  = LED_PWRGD_PVDDCR_CPU1_P1_D

R557  Q_RES  1K 1% EMPTY  pkg 0402LF  page 55 : A = PVDD18_S5_P1 ; B = PWRGD_CPU1_PWROK

(kicad_pcb
	(version 20260206)
	(generator "pcbnew")
	(generator_version "10.0")
	(general
		(thickness 1.6)
		(legacy_teardrops no)
	)
	(paper "A4")
	(title_block
		(title "04192023_DAF0TMB3IC0_F0TG_MB_C_brd_V02_OCP.brd")
		(comment 1 "Grand Teton / footprints 6997-6999 of 8354")
	)
	(layers
		(0 "F.Cu" signal "TOP")
		(4 "In1.Cu" signal "GND")
		(6 "In2.Cu" signal "IN1")
		(8 "In3.Cu" signal "GND1")
		(10 "In4.Cu" signal "IN2")
		(12 "In5.Cu" signal "GND2")
		(14 "In6.Cu" signal "IN3")
		(16 "In7.Cu" signal "GND3")
		(18 "In8.Cu" signal "VCC")
		(20 "In9.Cu" signal "VCC1")
		(22 "In10.Cu" signal "GND4")
		(24 "In11.Cu" signal "IN4")
		(26 "In12.Cu" signal "GND5")
		(28 "In13.Cu" signal "IN5")
		(30 "In14.Cu" signal "GND6")
		(32 "In15.Cu" signal "IN6")
		(34 "In16.Cu" signal "GND7")
		(2 "B.Cu" signal "BOTTOM")
		(9 "F.Adhes" user "F.Adhesive")
		(11 "B.Adhes" user "B.Adhesive")
		(13 "F.Paste" user "Package Geometry/Pastemask Top")
		(15 "B.Paste" user "Package Geometry/Pastemask Bottom")
		(5 "F.SilkS" user "Ref Des/Silkscreen Top")
		(7 "B.SilkS" user "Ref Des/Silkscreen Bottom")
		(1 "F.Mask" user "Board Geometry/Soldermask Top")
		(3 "B.Mask" user "Board Geometry/Soldermask Bottom")
		(17 "Dwgs.User" user "User.Drawings")
		(19 "Cmts.User" user "User.Comments")
		(21 "Eco1.User" user "User.Eco1")
		(23 "Eco2.User" user "User.Eco2")
		(25 "Edge.Cuts" user "Board Geometry/Outline")
		(27 "Margin" user)
		(31 "F.CrtYd" user "Package Geometry/Place Bound Top")
		(29 "B.CrtYd" user "Package Geometry/Place Bound Bottom")
		(35 "F.Fab" user "Ref Des/Assembly Top")
		(33 "B.Fab" user "Ref Des/Assembly Bottom")
	)
	(footprint ""
		(layer "B.Cu")
		(at 342.624664 -73.534778)
		(property "Reference" "Q85"
			(at 1.4224 -1.768348 0)
			(unlocked yes)
			(layer "B.SilkS")
			(effects
				(font
					(size 0.7874 0.5842)
					(thickness 0.1524)
				)
				(justify left mirror)
			)
		)
		(property "Value" ""
			(at 0 0 0)
			(layer "B.Fab")
			(effects
				(font
					(size 1.27 1.27)
				)
				(justify mirror)
			)
		)
		(duplicate_pad_numbers_are_jumpers no)
		(fp_line
			(start -1.332738 -1.100074)
			(end -1.332738 1.100074)
			(stroke
				(width 0.1524)
				(type default)
			)
			(layer "B.SilkS")
		)
		(fp_line
			(start -1.332738 1.100074)
			(end 1.332738 1.100074)
			(stroke
				(width 0.1524)
				(type default)
			)
			(layer "B.SilkS")
		)
		(fp_line
			(start -0.4826 -1.100074)
			(end -1.332738 -1.100074)
			(stroke
				(width 0.1524)
				(type default)
			)
			(layer "B.SilkS")
		)
		(fp_line
			(start 0 -0.541274)
			(end -0.4826 -1.100074)
			(stroke
				(width 0.1524)
				(type default)
			)
			(layer "B.SilkS")
		)
		(fp_line
			(start 0.4826 -1.100074)
			(end 0 -0.541274)
			(stroke
				(width 0.1524)
				(type default)
			)
			(layer "B.SilkS")
		)
		(fp_line
			(start 1.332738 -1.100074)
			(end 0.4826 -1.100074)
			(stroke
				(width 0.1524)
				(type default)
			)
			(layer "B.SilkS")
		)
		(fp_line
			(start 1.332738 1.100074)
			(end 1.332738 -1.100074)
			(stroke
				(width 0.1524)
				(type default)
			)
			(layer "B.SilkS")
		)
		(fp_poly
			(pts
				(xy 1.345692 -0.649986) (xy 2.047748 -1.001014) (xy 2.047748 -0.298958)
			)
			(stroke
				(width 0)
				(type default)
			)
			(fill yes)
			(layer "B.SilkS")
		)
		(fp_line
			(start -0.674878 -1.100074)
			(end -0.674878 1.100074)
			(stroke
				(width 0.1)
				(type default)
			)
			(layer "B.Fab")
		)
		(fp_line
			(start -0.674878 1.100074)
			(end 0.674878 1.100074)
			(stroke
				(width 0.1)
				(type default)
			)
			(layer "B.Fab")
		)
		(fp_line
			(start 0.674878 -1.100074)
			(end -0.674878 -1.100074)
			(stroke
				(width 0.1)
				(type default)
			)
			(layer "B.Fab")
		)
		(fp_line
			(start 0.674878 1.100074)
			(end 0.674878 -1.100074)
			(stroke
				(width 0.1)
				(type default)
			)
			(layer "B.Fab")
		)
		(fp_poly
			(pts
				(xy 2.2352 -0.298958) (xy 2.2352 -1.001014) (xy 1.533144 -0.649986)
			)
			(stroke
				(width 0)
				(type default)
			)
			(fill yes)
			(layer "B.Fab")
		)
		(pad "1" smd rect
			(at 0.94996 -0.649986 90)
			(size 0.4318 0.508)
			(layers "B.Cu" "B.Mask" "B.Paste")
			(net "GND")
		)
		(pad "2" smd rect
			(at 0.94996 0 90)
			(size 0.4318 0.508)
			(layers "B.Cu" "B.Mask" "B.Paste")
			(net "FM_LED_PWRGD_PVDDCR_CPU1_P1")
		)
		(pad "3" smd rect
			(at 0.94996 0.649986 90)
			(size 0.4318 0.508)
			(layers "B.Cu" "B.Mask" "B.Paste")
			(net "LED_PWRGD_PVDDIO_P1_D")
		)
		(pad "4" smd rect
			(at -0.94996 0.649986 90)
			(size 0.4318 0.508)
			(layers "B.Cu" "B.Mask" "B.Paste")
			(net "GND")
		)
		(pad "5" smd rect
			(at -0.94996 0 90)
			(size 0.4318 0.508)
			(layers "B.Cu" "B.Mask" "B.Paste")
			(net "FM_LED_PWRGD_PVDDIO_P1")
		)
		(pad "6" smd rect
			(at -0.94996 -0.649986 90)
			(size 0.4318 0.508)
			(layers "B.Cu" "B.Mask" "B.Paste")
			(net "LED_PWRGD_PVDDCR_CPU1_P1_D")
		)
	)
	(footprint ""
		(layer "B.Cu")
		(at 161.406332 -386.766562 90)
		(property "Reference" "C387"
			(at 0 0 90)
			(layer "B.SilkS")
			(hide yes)
			(effects
				(font
					(size 1.27 1.27)
				)
				(justify mirror)
			)
		)
		(property "Value" ""
			(at 0 0 90)
			(layer "B.Fab")
			(effects
				(font
					(size 1.27 1.27)
				)
				(justify mirror)
			)
		)
		(duplicate_pad_numbers_are_jumpers no)
		(fp_line
			(start 0.299974 -0.150114)
			(end -0.299974 -0.150114)
			(stroke
				(width 0.1)
				(type default)
			)
			(layer "B.Fab")
		)
		(fp_line
			(start -0.299974 -0.150114)
			(end -0.299974 0.150114)
			(stroke
				(width 0.1)
				(type default)
			)
			(layer "B.Fab")
		)
		(fp_line
			(start 0.299974 0.150114)
			(end 0.299974 -0.150114)
			(stroke
				(width 0.1)
				(type default)
			)
			(layer "B.Fab")
		)
		(fp_line
			(start -0.299974 0.150114)
			(end 0.299974 0.150114)
			(stroke
				(width 0.1)
				(type default)
			)
			(layer "B.Fab")
		)
		(pad "1" smd rect
			(at 0.2667 0 270)
			(size 0.3048 0.381)
			(layers "B.Cu" "B.Mask" "B.Paste")
			(net "P0V9_CPU1_RT2_2A")
		)
		(pad "2" smd rect
			(at -0.2667 0 270)
			(size 0.3048 0.381)
			(layers "B.Cu" "B.Mask" "B.Paste")
			(net "GND")
		)
	)
	(footprint ""
		(layer "B.Cu")
		(at 72.072754 -204.228192 180)
		(property "Reference" "R557"
			(at 0 0 0)
			(layer "B.SilkS")
			(hide yes)
			(effects
				(font
					(size 1.27 1.27)
				)
				(justify mirror)
			)
		)
		(property "Value" ""
			(at 0 0 0)
			(layer "B.Fab")
			(effects
				(font
					(size 1.27 1.27)
				)
				(justify mirror)
			)
		)
		(duplicate_pad_numbers_are_jumpers no)
		(fp_line
			(start 0.7874 0.4064)
			(end 0.7874 -0.4064)
			(stroke
				(width 0.1524)
				(type default)
			)
			(layer "B.SilkS")
		)
		(fp_line
			(start 0.7874 -0.4064)
			(end -0.7874 -0.4064)
			(stroke
				(width 0.1524)
				(type default)
			)
			(layer "B.SilkS")
		)
		(fp_line
			(start -0.7874 0.4064)
			(end 0.7874 0.4064)
			(stroke
				(width 0.1524)
				(type default)
			)
			(layer "B.SilkS")
		)
		(fp_line
			(start -0.7874 -0.4064)
			(end -0.7874 0.4064)
			(stroke
				(width 0.1524)
				(type default)
			)
			(layer "B.SilkS")
		)
		(fp_line
			(start 0.67945 0.3048)
			(end 0.67945 -0.305054)
			(stroke
				(width 0.1)
				(type default)
			)
			(layer "B.Fab")
		)
		(fp_line
			(start 0.67945 -0.305054)
			(end 0.12065 -0.305054)
			(stroke
				(width 0.1)
				(type default)
			)
			(layer "B.Fab")
		)
		(fp_line
			(start 0.12065 0.3048)
			(end 0.67945 0.3048)
			(stroke
				(width 0.1)
				(type default)
			)
			(layer "B.Fab")
		)
		(fp_line
			(start 0.12065 0.2794)
			(end 0.12065 0.3048)
			(stroke
				(width 0.1)
				(type default)
			)
			(layer "B.Fab")
		)
		(fp_line
			(start 0.12065 -0.2794)
			(end -0.12065 -0.2794)
			(stroke
				(width 0.1)
				(type default)
			)
			(layer "B.Fab")
		)
		(fp_line
			(start 0.12065 -0.305054)
			(end 0.12065 -0.2794)
			(stroke
				(width 0.1)
				(type default)
			)
			(layer "B.Fab")
		)
		(fp_line
			(start -0.120396 0.3048)
			(end -0.120396 0.2794)
			(stroke
				(width 0.1)
				(type default)
			)
			(layer "B.Fab")
		)
		(fp_line
			(start -0.120396 0.2794)
			(end 0.12065 0.2794)
			(stroke
				(width 0.1)
				(type default)
			)
			(layer "B.Fab")
		)
		(fp_line
			(start -0.12065 -0.2794)
			(end -0.12065 -0.3048)
			(stroke
				(width 0.1)
				(type default)
			)
			(layer "B.Fab")
		)
		(fp_line
			(start -0.12065 -0.3048)
			(end -0.67945 -0.3048)
			(stroke
				(width 0.1)
				(type default)
			)
			(layer "B.Fab")
		)
		(fp_line
			(start -0.67945 0.3048)
			(end -0.120396 0.3048)
			(stroke
				(width 0.1)
				(type default)
			)
			(layer "B.Fab")
		)
		(fp_line
			(start -0.67945 -0.3048)
			(end -0.67945 0.3048)
			(stroke
				(width 0.1)
				(type default)
			)
			(layer "B.Fab")
		)
		(pad "1" smd circle
			(at 0.40005 0)
			(size 0 0)
			(layers "B.Cu" "B.Mask" "B.Paste")
			(net "PVDD18_S5_P1")
		)
		(pad "2" smd circle
			(at -0.40005 0)
			(size 0 0)
			(layers "B.Cu" "B.Mask" "B.Paste")
			(net "PWRGD_CPU1_PWROK")
		)
	)
)
